(kicad_pcb
	(version 20221018)
	(generator pcbnew)
	(general
    (thickness 1.656)
  )
	(paper "A4")
	(title_block
    (title "SDI-MIPI Bridge")
    (date "2023-08-09")
    (rev "1.3.4")
    (company "Antmicro")
		(comment 9 "footprints 175-184 of 190")
	)
	(layers
    (0 "F.Cu" signal)
    (1 "In1.Cu" power)
    (2 "In2.Cu" power)
    (3 "In3.Cu" signal)
    (4 "In4.Cu" signal)
    (31 "B.Cu" signal)
    (32 "B.Adhes" user "B.Adhesive")
    (33 "F.Adhes" user "F.Adhesive")
    (34 "B.Paste" user)
    (35 "F.Paste" user)
    (36 "B.SilkS" user "B.Silkscreen")
    (37 "F.SilkS" user "F.Silkscreen")
    (38 "B.Mask" user)
    (39 "F.Mask" user)
    (40 "Dwgs.User" user "User.Drawings")
    (41 "Cmts.User" user "User.Comments")
    (42 "Eco1.User" user "User.Eco1")
    (43 "Eco2.User" user "User.Eco2")
    (44 "Edge.Cuts" user)
    (45 "Margin" user)
    (46 "B.CrtYd" user "B.Courtyard")
    (47 "F.CrtYd" user "F.Courtyard")
    (48 "B.Fab" user)
    (49 "F.Fab" user)
  )
	(footprint "sdi-mipi-bridge-footprints:R_0402_1005Metric" (layer "B.Cu")
    (at 152.795 107.61)
    (descr "Resistor SMD 0402")
    (tags "resistor SMD 0402")
    (property "Author" "Antmicro")
    (property "DNP" "DNP")
    (property "License" "Apache-2.0")
    (property "MPN" "CR0402-FX-2201GLF")
    (property "Manufacturer" "Bourns")
    (property "Sheetfile" "sdi-mipi-bridge.kicad_sch")
    (property "Sheetname" "")
    (property "Tolerance" "1%")
    (property "Val" "2k2")
    (property "ki_description" "2k2 resistor in 0402 package with 1% tolerance")
    (attr exclude_from_pos_files)
    (fp_text reference "R86" (at 3.005 -4.81 180) (layer "B.SilkS")
        (effects (font (size 0.7 0.7) (thickness 0.15)) (justify left bottom mirror))
    )
    (fp_text value "R_2k2_0402" (at 0 -1.4 180) (layer "B.Fab") hide
        (effects (font (size 0.7 0.7) (thickness 0.15)) (justify left bottom mirror))
    )
    (fp_text user "${REFERENCE}" (at -0.95 -3.168 180) (layer "B.Fab") hide
        (effects (font (size 0.7 0.7) (thickness 0.15)) (justify left bottom mirror))
    )
    (fp_text user "Author: Antmicro" (at -0.95 -4.169 180) (layer "B.Fab") hide
        (effects (font (size 0.7 0.7) (thickness 0.15)) (justify left bottom mirror))
    )
    (fp_text user "License: Apache-2.0" (at -0.95 -5.169 180) (layer "B.Fab") hide
        (effects (font (size 0.7 0.7) (thickness 0.15)) (justify left bottom mirror))
    )
    (fp_rect (start -0.93 0.47) (end 0.93 -0.47)
      (stroke (width 0.05) (type solid)) (fill none) (layer "B.CrtYd"))
    (fp_rect (start -0.5 0.25) (end 0.5 -0.25)
      (stroke (width 0.15) (type solid)) (fill none) (layer "B.Fab"))
    (pad "1" smd roundrect (at -0.485 0) (size 0.59 0.64) (layers "B.Cu" "B.Paste" "B.Mask") (roundrect_rratio 0.25)
      (net 98 "Net-(R67-Pad2)") (pintype "passive"))
    (pad "2" smd roundrect (at 0.485 0) (size 0.59 0.64) (layers "B.Cu" "B.Paste" "B.Mask") (roundrect_rratio 0.25)
      (net 102 "/SPI_SCK(SDA)") (pintype "passive"))
  )
	(footprint "sdi-mipi-bridge-footprints:R_0402_1005Metric" (layer "B.Cu")
    (at 152.795 108.81)
    (descr "Resistor SMD 0402")
    (tags "resistor SMD 0402")
    (property "Author" "Antmicro")
    (property "DNP" "DNP")
    (property "License" "Apache-2.0")
    (property "MPN" "CR0402-FX-2201GLF")
    (property "Manufacturer" "Bourns")
    (property "Sheetfile" "sdi-mipi-bridge.kicad_sch")
    (property "Sheetname" "")
    (property "Tolerance" "1%")
    (property "Val" "2k2")
    (property "ki_description" "2k2 resistor in 0402 package with 1% tolerance")
    (attr exclude_from_pos_files)
    (fp_text reference "R87" (at 3.005 -4.81 180) (layer "B.SilkS")
        (effects (font (size 0.7 0.7) (thickness 0.15)) (justify left bottom mirror))
    )
    (fp_text value "R_2k2_0402" (at 0 -1.4 180) (layer "B.Fab") hide
        (effects (font (size 0.7 0.7) (thickness 0.15)) (justify left bottom mirror))
    )
    (fp_text user "Author: Antmicro" (at -0.95 -4.169 180) (layer "B.Fab") hide
        (effects (font (size 0.7 0.7) (thickness 0.15)) (justify left bottom mirror))
    )
    (fp_text user "${REFERENCE}" (at -0.95 -3.168 180) (layer "B.Fab") hide
        (effects (font (size 0.7 0.7) (thickness 0.15)) (justify left bottom mirror))
    )
    (fp_text user "License: Apache-2.0" (at -0.95 -5.169 180) (layer "B.Fab") hide
        (effects (font (size 0.7 0.7) (thickness 0.15)) (justify left bottom mirror))
    )
    (fp_rect (start -0.93 0.47) (end 0.93 -0.47)
      (stroke (width 0.05) (type solid)) (fill none) (layer "B.CrtYd"))
    (fp_rect (start -0.5 0.25) (end 0.5 -0.25)
      (stroke (width 0.15) (type solid)) (fill none) (layer "B.Fab"))
    (pad "1" smd roundrect (at -0.485 0) (size 0.59 0.64) (layers "B.Cu" "B.Paste" "B.Mask") (roundrect_rratio 0.25)
      (net 98 "Net-(R67-Pad2)") (pintype "passive"))
    (pad "2" smd roundrect (at 0.485 0) (size 0.59 0.64) (layers "B.Cu" "B.Paste" "B.Mask") (roundrect_rratio 0.25)
      (net 61 "/SCL_GS") (pintype "passive"))
  )
	(footprint "sdi-mipi-bridge-footprints:R_0402_1005Metric" (layer "B.Cu")
    (at 152.795 110.01)
    (descr "Resistor SMD 0402")
    (tags "resistor SMD 0402")
    (property "Author" "Antmicro")
    (property "DNP" "DNP")
    (property "License" "Apache-2.0")
    (property "MPN" "CR0402-FX-2201GLF")
    (property "Manufacturer" "Bourns")
    (property "Sheetfile" "sdi-mipi-bridge.kicad_sch")
    (property "Sheetname" "")
    (property "Tolerance" "1%")
    (property "Val" "2k2")
    (property "ki_description" "2k2 resistor in 0402 package with 1% tolerance")
    (attr exclude_from_pos_files)
    (fp_text reference "R94" (at 3.005 -4.81 180) (layer "B.SilkS")
        (effects (font (size 0.7 0.7) (thickness 0.15)) (justify left bottom mirror))
    )
    (fp_text value "R_2k2_0402" (at 0 -1.4 180) (layer "B.Fab") hide
        (effects (font (size 0.7 0.7) (thickness 0.15)) (justify left bottom mirror))
    )
    (fp_text user "Author: Antmicro" (at -0.95 -4.169 180) (layer "B.Fab") hide
        (effects (font (size 0.7 0.7) (thickness 0.15)) (justify left bottom mirror))
    )
    (fp_text user "License: Apache-2.0" (at -0.95 -5.169 180) (layer "B.Fab") hide
        (effects (font (size 0.7 0.7) (thickness 0.15)) (justify left bottom mirror))
    )
    (fp_text user "${REFERENCE}" (at -0.95 -3.168 180) (layer "B.Fab") hide
        (effects (font (size 0.7 0.7) (thickness 0.15)) (justify left bottom mirror))
    )
    (fp_rect (start -0.93 0.47) (end 0.93 -0.47)
      (stroke (width 0.05) (type solid)) (fill none) (layer "B.CrtYd"))
    (fp_rect (start -0.5 0.25) (end 0.5 -0.25)
      (stroke (width 0.15) (type solid)) (fill none) (layer "B.Fab"))
    (pad "1" smd roundrect (at -0.485 0) (size 0.59 0.64) (layers "B.Cu" "B.Paste" "B.Mask") (roundrect_rratio 0.25)
      (net 98 "Net-(R67-Pad2)") (pintype "passive"))
    (pad "2" smd roundrect (at 0.485 0) (size 0.59 0.64) (layers "B.Cu" "B.Paste" "B.Mask") (roundrect_rratio 0.25)
      (net 62 "/SDA_GS") (pintype "passive"))
  )
	(footprint "sdi-mipi-bridge-footprints:C_0402_1005Metric" (layer "B.Cu")
    (at 126.1 134.53 180)
    (descr "Capacitor SMD 0402")
    (tags "capacitor SMD 0402")
    (property "Author" "Antmicro")
    (property "Dielectric" "X7R")
    (property "License" "Apache-2.0")
    (property "MPN" "GRM155R71H103KA88D")
    (property "Manufacturer" "Murata")
    (property "Sheetfile" "sdi-mipi-bridge.kicad_sch")
    (property "Sheetname" "")
    (property "Val" "10n")
    (property "Voltage" "50V")
    (property "ki_description" " ")
    (attr smd)
    (fp_text reference "C19" (at 1.301 -0.35) (layer "B.SilkS")
        (effects (font (size 0.7 0.7) (thickness 0.15)) (justify left bottom mirror))
    )
    (fp_text value "C_10n_0402" (at 0 -1.4) (layer "B.Fab") hide
        (effects (font (size 0.7 0.7) (thickness 0.15)) (justify left bottom mirror))
    )
    (fp_text user "${REFERENCE}" (at -0.932 -3.168) (layer "B.Fab") hide
        (effects (font (size 0.7 0.7) (thickness 0.15)) (justify left bottom mirror))
    )
    (fp_text user "License: Apache-2.0" (at -0.932 -5.17) (layer "B.Fab") hide
        (effects (font (size 0.7 0.7) (thickness 0.15)) (justify left bottom mirror))
    )
    (fp_text user "Author: Antmicro" (at -0.932 -4.17) (layer "B.Fab") hide
        (effects (font (size 0.7 0.7) (thickness 0.15)) (justify left bottom mirror))
    )
    (fp_rect (start -0.94 0.47) (end 0.94 -0.47)
      (stroke (width 0.05) (type solid)) (fill none) (layer "B.CrtYd"))
    (fp_rect (start -0.499 0.249) (end 0.499 -0.249)
      (stroke (width 0.15) (type solid)) (fill none) (layer "B.Fab"))
    (pad "1" smd roundrect (at -0.484 0 180) (size 0.59 0.64) (layers "B.Cu" "B.Paste" "B.Mask") (roundrect_rratio 0.25)
      (net 1 "GNDREF") (pintype "passive"))
    (pad "2" smd roundrect (at 0.484 0 180) (size 0.59 0.64) (layers "B.Cu" "B.Paste" "B.Mask") (roundrect_rratio 0.25)
      (net 6 "+3V3") (pintype "passive"))
  )
	(footprint "sdi-mipi-bridge-footprints:R_0402_1005Metric" (layer "B.Cu")
    (at 126.1 135.55 180)
    (descr "Resistor SMD 0402")
    (tags "resistor SMD 0402")
    (property "Author" "Antmicro")
    (property "Current" "1A")
    (property "License" "Apache-2.0")
    (property "MPN" "ERJ2GE0R00X")
    (property "Manufacturer" "Panasonic")
    (property "Sheetfile" "sdi-mipi-bridge.kicad_sch")
    (property "Sheetname" "")
    (property "Tolerance" "")
    (property "Val" "0R")
    (property "ki_description" "0R resistor in 0402 package with unspecified tolerance")
    (attr smd)
    (fp_text reference "R22" (at 1.3 -0.35) (layer "B.SilkS")
        (effects (font (size 0.7 0.7) (thickness 0.15)) (justify left bottom mirror))
    )
    (fp_text value "R_0R_0402" (at 0 -1.4) (layer "B.Fab") hide
        (effects (font (size 0.7 0.7) (thickness 0.15)) (justify left bottom mirror))
    )
    (fp_text user "Author: Antmicro" (at -0.95 -4.169) (layer "B.Fab") hide
        (effects (font (size 0.7 0.7) (thickness 0.15)) (justify left bottom mirror))
    )
    (fp_text user "${REFERENCE}" (at -0.95 -3.168) (layer "B.Fab") hide
        (effects (font (size 0.7 0.7) (thickness 0.15)) (justify left bottom mirror))
    )
    (fp_text user "License: Apache-2.0" (at -0.95 -5.169) (layer "B.Fab") hide
        (effects (font (size 0.7 0.7) (thickness 0.15)) (justify left bottom mirror))
    )
    (fp_rect (start -0.93 0.47) (end 0.93 -0.47)
      (stroke (width 0.05) (type solid)) (fill none) (layer "B.CrtYd"))
    (fp_rect (start -0.5 0.25) (end 0.5 -0.25)
      (stroke (width 0.15) (type solid)) (fill none) (layer "B.Fab"))
    (pad "1" smd roundrect (at -0.485 0 180) (size 0.59 0.64) (layers "B.Cu" "B.Paste" "B.Mask") (roundrect_rratio 0.25)
      (net 1 "GNDREF") (pintype "passive"))
    (pad "2" smd roundrect (at 0.485 0 180) (size 0.59 0.64) (layers "B.Cu" "B.Paste" "B.Mask") (roundrect_rratio 0.25)
      (net 3 "GNDA") (pintype "passive"))
  )
	(footprint "sdi-mipi-bridge-footprints:R_0402_1005Metric" (layer "B.Cu")
    (at 133.645001 122.932)
    (descr "Resistor SMD 0402")
    (tags "resistor SMD 0402")
    (property "Author" "Antmicro")
    (property "Current" "1A")
    (property "License" "Apache-2.0")
    (property "MPN" "ERJ2GE0R00X")
    (property "Manufacturer" "Panasonic")
    (property "Sheetfile" "sdi-mipi-bridge.kicad_sch")
    (property "Sheetname" "")
    (property "Tolerance" "")
    (property "Val" "0R")
    (property "ki_description" "0R resistor in 0402 package with unspecified tolerance")
    (attr smd)
    (fp_text reference "R74" (at 1.154999 3.468 180) (layer "B.SilkS")
        (effects (font (size 0.7 0.7) (thickness 0.15)) (justify left bottom mirror))
    )
    (fp_text value "R_0R_0402" (at 0 -1.4) (layer "B.Fab") hide
        (effects (font (size 0.7 0.7) (thickness 0.15)) (justify right bottom mirror))
    )
    (fp_text user "License: Apache-2.0" (at -0.95 -5.169) (layer "B.Fab") hide
        (effects (font (size 0.7 0.7) (thickness 0.15)) (justify right bottom mirror))
    )
    (fp_text user "Author: Antmicro" (at -0.95 -4.169) (layer "B.Fab") hide
        (effects (font (size 0.7 0.7) (thickness 0.15)) (justify right bottom mirror))
    )
    (fp_text user "${REFERENCE}" (at -0.95 -3.168) (layer "B.Fab") hide
        (effects (font (size 0.7 0.7) (thickness 0.15)) (justify right bottom mirror))
    )
    (fp_rect (start -0.93 0.47) (end 0.93 -0.47)
      (stroke (width 0.05) (type solid)) (fill none) (layer "B.CrtYd"))
    (fp_rect (start -0.5 0.25) (end 0.5 -0.25)
      (stroke (width 0.15) (type solid)) (fill none) (layer "B.Fab"))
    (pad "1" smd roundrect (at -0.485 0) (size 0.59 0.64) (layers "B.Cu" "B.Paste" "B.Mask") (roundrect_rratio 0.25)
      (net 84 "Net-(U5-A2)") (pintype "passive"))
    (pad "2" smd roundrect (at 0.485 0) (size 0.59 0.64) (layers "B.Cu" "B.Paste" "B.Mask") (roundrect_rratio 0.25)
      (net 1 "GNDREF") (pintype "passive"))
  )
	(footprint "sdi-mipi-bridge-footprints:R_0402_1005Metric" (layer "B.Cu")
    (at 133.645001 123.932 180)
    (descr "Resistor SMD 0402")
    (tags "resistor SMD 0402")
    (property "Author" "Antmicro")
    (property "Current" "1A")
    (property "License" "Apache-2.0")
    (property "MPN" "ERJ2GE0R00X")
    (property "Manufacturer" "Panasonic")
    (property "Sheetfile" "sdi-mipi-bridge.kicad_sch")
    (property "Sheetname" "")
    (property "Tolerance" "")
    (property "Val" "0R")
    (property "ki_description" "0R resistor in 0402 package with unspecified tolerance")
    (attr smd)
    (fp_text reference "R73" (at -1.154999 -3.468) (layer "B.SilkS")
        (effects (font (size 0.7 0.7) (thickness 0.15)) (justify left bottom mirror))
    )
    (fp_text value "R_0R_0402" (at 0 -1.4) (layer "B.Fab") hide
        (effects (font (size 0.7 0.7) (thickness 0.15)) (justify left bottom mirror))
    )
    (fp_text user "License: Apache-2.0" (at -0.95 -5.169) (layer "B.Fab") hide
        (effects (font (size 0.7 0.7) (thickness 0.15)) (justify left bottom mirror))
    )
    (fp_text user "Author: Antmicro" (at -0.95 -4.169) (layer "B.Fab") hide
        (effects (font (size 0.7 0.7) (thickness 0.15)) (justify left bottom mirror))
    )
    (fp_text user "${REFERENCE}" (at -0.95 -3.168) (layer "B.Fab") hide
        (effects (font (size 0.7 0.7) (thickness 0.15)) (justify left bottom mirror))
    )
    (fp_rect (start -0.93 0.47) (end 0.93 -0.47)
      (stroke (width 0.05) (type solid)) (fill none) (layer "B.CrtYd"))
    (fp_rect (start -0.5 0.25) (end 0.5 -0.25)
      (stroke (width 0.15) (type solid)) (fill none) (layer "B.Fab"))
    (pad "1" smd roundrect (at -0.485 0 180) (size 0.59 0.64) (layers "B.Cu" "B.Paste" "B.Mask") (roundrect_rratio 0.25)
      (net 75 "Net-(U5-A1)") (pintype "passive"))
    (pad "2" smd roundrect (at 0.485 0 180) (size 0.59 0.64) (layers "B.Cu" "B.Paste" "B.Mask") (roundrect_rratio 0.25)
      (net 1 "GNDREF") (pintype "passive"))
  )
	(footprint "sdi-mipi-bridge-footprints:R_0402_1005Metric" (layer "B.Cu")
    (at 133.645001 124.932 180)
    (descr "Resistor SMD 0402")
    (tags "resistor SMD 0402")
    (property "Author" "Antmicro")
    (property "Current" "1A")
    (property "License" "Apache-2.0")
    (property "MPN" "ERJ2GE0R00X")
    (property "Manufacturer" "Panasonic")
    (property "Sheetfile" "sdi-mipi-bridge.kicad_sch")
    (property "Sheetname" "")
    (property "Tolerance" "")
    (property "Val" "0R")
    (property "ki_description" "0R resistor in 0402 package with unspecified tolerance")
    (attr smd)
    (fp_text reference "R72" (at -1.154999 -3.468) (layer "B.SilkS")
        (effects (font (size 0.7 0.7) (thickness 0.15)) (justify left bottom mirror))
    )
    (fp_text value "R_0R_0402" (at 0 -1.4) (layer "B.Fab") hide
        (effects (font (size 0.7 0.7) (thickness 0.15)) (justify left bottom mirror))
    )
    (fp_text user "${REFERENCE}" (at -0.95 -3.168) (layer "B.Fab") hide
        (effects (font (size 0.7 0.7) (thickness 0.15)) (justify left bottom mirror))
    )
    (fp_text user "License: Apache-2.0" (at -0.95 -5.169) (layer "B.Fab") hide
        (effects (font (size 0.7 0.7) (thickness 0.15)) (justify left bottom mirror))
    )
    (fp_text user "Author: Antmicro" (at -0.95 -4.169) (layer "B.Fab") hide
        (effects (font (size 0.7 0.7) (thickness 0.15)) (justify left bottom mirror))
    )
    (fp_rect (start -0.93 0.47) (end 0.93 -0.47)
      (stroke (width 0.05) (type solid)) (fill none) (layer "B.CrtYd"))
    (fp_rect (start -0.5 0.25) (end 0.5 -0.25)
      (stroke (width 0.15) (type solid)) (fill none) (layer "B.Fab"))
    (pad "1" smd roundrect (at -0.485 0 180) (size 0.59 0.64) (layers "B.Cu" "B.Paste" "B.Mask") (roundrect_rratio 0.25)
      (net 74 "Net-(U5-A0)") (pintype "passive"))
    (pad "2" smd roundrect (at 0.485 0 180) (size 0.59 0.64) (layers "B.Cu" "B.Paste" "B.Mask") (roundrect_rratio 0.25)
      (net 1 "GNDREF") (pintype "passive"))
  )
	(footprint "sdi-mipi-bridge-footprints:R_0402_1005Metric" (layer "B.Cu")
    (at 126.1 130.45 180)
    (descr "Resistor SMD 0402")
    (tags "resistor SMD 0402")
    (property "Author" "Antmicro")
    (property "Current" "1A")
    (property "License" "Apache-2.0")
    (property "MPN" "ERJ2GE0R00X")
    (property "Manufacturer" "Panasonic")
    (property "Sheetfile" "sdi-mipi-bridge.kicad_sch")
    (property "Sheetname" "")
    (property "Tolerance" "")
    (property "Val" "0R")
    (property "ki_description" "0R resistor in 0402 package with unspecified tolerance")
    (attr smd)
    (fp_text reference "R21" (at 1.3 -0.35) (layer "B.SilkS")
        (effects (font (size 0.7 0.7) (thickness 0.15)) (justify left bottom mirror))
    )
    (fp_text value "R_0R_0402" (at 0 -1.4) (layer "B.Fab") hide
        (effects (font (size 0.7 0.7) (thickness 0.15)) (justify left bottom mirror))
    )
    (fp_text user "Author: Antmicro" (at -0.95 -4.169) (layer "B.Fab") hide
        (effects (font (size 0.7 0.7) (thickness 0.15)) (justify left bottom mirror))
    )
    (fp_text user "${REFERENCE}" (at -0.95 -3.168) (layer "B.Fab") hide
        (effects (font (size 0.7 0.7) (thickness 0.15)) (justify left bottom mirror))
    )
    (fp_text user "License: Apache-2.0" (at -0.95 -5.169) (layer "B.Fab") hide
        (effects (font (size 0.7 0.7) (thickness 0.15)) (justify left bottom mirror))
    )
    (fp_rect (start -0.93 0.47) (end 0.93 -0.47)
      (stroke (width 0.05) (type solid)) (fill none) (layer "B.CrtYd"))
    (fp_rect (start -0.5 0.25) (end 0.5 -0.25)
      (stroke (width 0.15) (type solid)) (fill none) (layer "B.Fab"))
    (pad "1" smd roundrect (at -0.485 0 180) (size 0.59 0.64) (layers "B.Cu" "B.Paste" "B.Mask") (roundrect_rratio 0.25)
      (net 6 "+3V3") (pintype "passive"))
    (pad "2" smd roundrect (at 0.485 0 180) (size 0.59 0.64) (layers "B.Cu" "B.Paste" "B.Mask") (roundrect_rratio 0.25)
      (net 5 "+3.3VA") (pintype "passive"))
  )
	(footprint "sdi-mipi-bridge-footprints:R_0402_1005Metric" (layer "B.Cu")
    (at 130.4 127.9)
    (descr "Resistor SMD 0402")
    (tags "resistor SMD 0402")
    (property "Author" "Antmicro")
    (property "Current" "1A")
    (property "License" "Apache-2.0")
    (property "MPN" "ERJ2GE0R00X")
    (property "Manufacturer" "Panasonic")
    (property "Sheetfile" "sdi-mipi-bridge.kicad_sch")
    (property "Sheetname" "")
    (property "Tolerance" "")
    (property "Val" "0R")
    (property "ki_description" "0R resistor in 0402 package with unspecified tolerance")
    (attr smd)
    (fp_text reference "R43" (at -1 0.3 180) (layer "B.SilkS")
        (effects (font (size 0.7 0.7) (thickness 0.15)) (justify left bottom mirror))
    )
    (fp_text value "R_0R_0402" (at 0 -1.4 180) (layer "B.Fab") hide
        (effects (font (size 0.7 0.7) (thickness 0.15)) (justify left bottom mirror))
    )
    (fp_text user "Author: Antmicro" (at -0.95 -4.169 180) (layer "B.Fab") hide
        (effects (font (size 0.7 0.7) (thickness 0.15)) (justify left bottom mirror))
    )
    (fp_text user "${REFERENCE}" (at -0.95 -3.168 180) (layer "B.Fab") hide
        (effects (font (size 0.7 0.7) (thickness 0.15)) (justify left bottom mirror))
    )
    (fp_text user "License: Apache-2.0" (at -0.95 -5.169 180) (layer "B.Fab") hide
        (effects (font (size 0.7 0.7) (thickness 0.15)) (justify left bottom mirror))
    )
    (fp_rect (start -0.93 0.47) (end 0.93 -0.47)
      (stroke (width 0.05) (type solid)) (fill none) (layer "B.CrtYd"))
    (fp_rect (start -0.5 0.25) (end 0.5 -0.25)
      (stroke (width 0.15) (type solid)) (fill none) (layer "B.Fab"))
    (pad "1" smd roundrect (at -0.485 0) (size 0.59 0.64) (layers "B.Cu" "B.Paste" "B.Mask") (roundrect_rratio 0.25)
      (net 6 "+3V3") (pintype "passive"))
    (pad "2" smd roundrect (at 0.485 0) (size 0.59 0.64) (layers "B.Cu" "B.Paste" "B.Mask") (roundrect_rratio 0.25)
      (net 72 "Net-(U5-~{RESET})") (pintype "passive"))
  )
)
